# T6G (Grand Teton) — schematic netlist excerpt (pin names and nets, part order shuffled) for the footprints in the layout excerpt that follows; sources: Cadence DE-HDL packaged netlist, KiCad conversion of 04192023_DAF0TMB3IC0_F0TG_MB_C_brd_V02_OCP.brd

R415  Q_RES  2.2K 5% CHIP  pkg 0402LF  page 27 : A = CPU0_XTRIG_L6 ; B = PVDD18_S5_P0
PC1849  Q_CAP  22UF 16V 20% X6S  pkg C0805  page 189 : A = SW_P5V_AUX_FLT ; B = GND
R1380  Q_RES  1K 1% CHIP  pkg 0201LF  page 320 : A = JTAG_TRST_RT_CPU1_P0_N ; B = GND

(kicad_pcb
	(version 20260206)
	(generator "pcbnew")
	(generator_version "10.0")
	(general
		(thickness 1.6)
		(legacy_teardrops no)
	)
	(paper "A4")
	(title_block
		(title "04192023_DAF0TMB3IC0_F0TG_MB_C_brd_V02_OCP.brd")
		(comment 1 "Grand Teton / footprints 1804-1806 of 8354")
	)
	(layers
		(0 "F.Cu" signal "TOP")
		(4 "In1.Cu" signal "GND")
		(6 "In2.Cu" signal "IN1")
		(8 "In3.Cu" signal "GND1")
		(10 "In4.Cu" signal "IN2")
		(12 "In5.Cu" signal "GND2")
		(14 "In6.Cu" signal "IN3")
		(16 "In7.Cu" signal "GND3")
		(18 "In8.Cu" signal "VCC")
		(20 "In9.Cu" signal "VCC1")
		(22 "In10.Cu" signal "GND4")
		(24 "In11.Cu" signal "IN4")
		(26 "In12.Cu" signal "GND5")
		(28 "In13.Cu" signal "IN5")
		(30 "In14.Cu" signal "GND6")
		(32 "In15.Cu" signal "IN6")
		(34 "In16.Cu" signal "GND7")
		(2 "B.Cu" signal "BOTTOM")
		(9 "F.Adhes" user "F.Adhesive")
		(11 "B.Adhes" user "B.Adhesive")
		(13 "F.Paste" user "Package Geometry/Pastemask Top")
		(15 "B.Paste" user "Package Geometry/Pastemask Bottom")
		(5 "F.SilkS" user "Ref Des/Silkscreen Top")
		(7 "B.SilkS" user "Ref Des/Silkscreen Bottom")
		(1 "F.Mask" user "Board Geometry/Soldermask Top")
		(3 "B.Mask" user "Board Geometry/Soldermask Bottom")
		(17 "Dwgs.User" user "User.Drawings")
		(19 "Cmts.User" user "User.Comments")
		(21 "Eco1.User" user "User.Eco1")
		(23 "Eco2.User" user "User.Eco2")
		(25 "Edge.Cuts" user "Board Geometry/Outline")
		(27 "Margin" user)
		(31 "F.CrtYd" user "Package Geometry/Place Bound Top")
		(29 "B.CrtYd" user "Package Geometry/Place Bound Bottom")
		(35 "F.Fab" user "Ref Des/Assembly Top")
		(33 "B.Fab" user "Ref Des/Assembly Bottom")
	)
	(footprint ""
		(layer "F.Cu")
		(at 327.323958 -193.163952 -90)
		(property "Reference" "R415"
			(at 0 0 270)
			(layer "F.SilkS")
			(hide yes)
			(effects
				(font
					(size 1.27 1.27)
				)
			)
		)
		(property "Value" ""
			(at 0 0 270)
			(layer "F.Fab")
			(effects
				(font
					(size 1.27 1.27)
				)
			)
		)
		(duplicate_pad_numbers_are_jumpers no)
		(fp_line
			(start -0.7874 0.4064)
			(end -0.7874 -0.4064)
			(stroke
				(width 0.1524)
				(type default)
			)
			(layer "F.SilkS")
		)
		(fp_line
			(start 0.7874 0.4064)
			(end -0.7874 0.4064)
			(stroke
				(width 0.1524)
				(type default)
			)
			(layer "F.SilkS")
		)
		(fp_line
			(start -0.7874 -0.4064)
			(end 0.7874 -0.4064)
			(stroke
				(width 0.1524)
				(type default)
			)
			(layer "F.SilkS")
		)
		(fp_line
			(start 0.7874 -0.4064)
			(end 0.7874 0.4064)
			(stroke
				(width 0.1524)
				(type default)
			)
			(layer "F.SilkS")
		)
		(fp_line
			(start -0.67945 0.3048)
			(end -0.67945 -0.305054)
			(stroke
				(width 0.1)
				(type default)
			)
			(layer "F.Fab")
		)
		(fp_line
			(start -0.12065 0.3048)
			(end -0.67945 0.3048)
			(stroke
				(width 0.1)
				(type default)
			)
			(layer "F.Fab")
		)
		(fp_line
			(start 0.120396 0.3048)
			(end 0.120396 0.2794)
			(stroke
				(width 0.1)
				(type default)
			)
			(layer "F.Fab")
		)
		(fp_line
			(start 0.67945 0.3048)
			(end 0.120396 0.3048)
			(stroke
				(width 0.1)
				(type default)
			)
			(layer "F.Fab")
		)
		(fp_line
			(start -0.12065 0.2794)
			(end -0.12065 0.3048)
			(stroke
				(width 0.1)
				(type default)
			)
			(layer "F.Fab")
		)
		(fp_line
			(start 0.120396 0.2794)
			(end -0.12065 0.2794)
			(stroke
				(width 0.1)
				(type default)
			)
			(layer "F.Fab")
		)
		(fp_line
			(start -0.12065 -0.2794)
			(end 0.12065 -0.2794)
			(stroke
				(width 0.1)
				(type default)
			)
			(layer "F.Fab")
		)
		(fp_line
			(start 0.12065 -0.2794)
			(end 0.12065 -0.3048)
			(stroke
				(width 0.1)
				(type default)
			)
			(layer "F.Fab")
		)
		(fp_line
			(start 0.12065 -0.3048)
			(end 0.67945 -0.3048)
			(stroke
				(width 0.1)
				(type default)
			)
			(layer "F.Fab")
		)
		(fp_line
			(start 0.67945 -0.3048)
			(end 0.67945 0.3048)
			(stroke
				(width 0.1)
				(type default)
			)
			(layer "F.Fab")
		)
		(fp_line
			(start -0.67945 -0.305054)
			(end -0.12065 -0.305054)
			(stroke
				(width 0.1)
				(type default)
			)
			(layer "F.Fab")
		)
		(fp_line
			(start -0.12065 -0.305054)
			(end -0.12065 -0.2794)
			(stroke
				(width 0.1)
				(type default)
			)
			(layer "F.Fab")
		)
		(pad "1" smd circle
			(at -0.40005 0 270)
			(size 0 0)
			(layers "F.Cu" "F.Mask" "F.Paste")
			(net "CPU0_XTRIG_L6")
		)
		(pad "2" smd circle
			(at 0.40005 0 270)
			(size 0 0)
			(layers "F.Cu" "F.Mask" "F.Paste")
			(net "PVDD18_S5_P0")
		)
	)
	(footprint ""
		(layer "F.Cu")
		(at 413.928306 -135.41502)
		(property "Reference" "PC1849"
			(at 0 0 0)
			(layer "F.SilkS")
			(hide yes)
			(effects
				(font
					(size 1.27 1.27)
				)
			)
		)
		(property "Value" ""
			(at 0 0 0)
			(layer "F.Fab")
			(effects
				(font
					(size 1.27 1.27)
				)
			)
		)
		(duplicate_pad_numbers_are_jumpers no)
		(fp_line
			(start -1.524 -0.762)
			(end 1.524 -0.762)
			(stroke
				(width 0.1524)
				(type default)
			)
			(layer "F.SilkS")
		)
		(fp_line
			(start -1.524 0.762)
			(end -1.524 -0.762)
			(stroke
				(width 0.1524)
				(type default)
			)
			(layer "F.SilkS")
		)
		(fp_line
			(start 1.524 -0.762)
			(end 1.524 0.762)
			(stroke
				(width 0.1524)
				(type default)
			)
			(layer "F.SilkS")
		)
		(fp_line
			(start 1.524 0.762)
			(end -1.524 0.762)
			(stroke
				(width 0.1524)
				(type default)
			)
			(layer "F.SilkS")
		)
		(fp_line
			(start -1.1049 -0.724916)
			(end -1.1049 0.724916)
			(stroke
				(width 0.1)
				(type default)
			)
			(layer "F.Fab")
		)
		(fp_line
			(start -1.1049 0.724916)
			(end 1.1049 0.724916)
			(stroke
				(width 0.1)
				(type default)
			)
			(layer "F.Fab")
		)
		(fp_line
			(start 1.1049 -0.724916)
			(end -1.1049 -0.724916)
			(stroke
				(width 0.1)
				(type default)
			)
			(layer "F.Fab")
		)
		(fp_line
			(start 1.1049 0.724916)
			(end 1.1049 -0.724916)
			(stroke
				(width 0.1)
				(type default)
			)
			(layer "F.Fab")
		)
		(pad "1" smd rect
			(at -0.889 0 180)
			(size 1.016 1.27)
			(layers "F.Cu" "F.Mask" "F.Paste")
			(net "SW_P5V_AUX_FLT")
		)
		(pad "2" smd rect
			(at 0.889 0 180)
			(size 1.016 1.27)
			(layers "F.Cu" "F.Mask" "F.Paste")
			(net "GND")
		)
	)
	(footprint ""
		(layer "F.Cu")
		(at 69.6976 -390.74598)
		(property "Reference" "R1380"
			(at 0 0 0)
			(layer "F.SilkS")
			(hide yes)
			(effects
				(font
					(size 1.27 1.27)
				)
			)
		)
		(property "Value" ""
			(at 0 0 0)
			(layer "F.Fab")
			(effects
				(font
					(size 1.27 1.27)
				)
			)
		)
		(duplicate_pad_numbers_are_jumpers no)
		(fp_line
			(start -0.32512 -0.175006)
			(end 0.32512 -0.175006)
			(stroke
				(width 0.1)
				(type default)
			)
			(layer "F.Fab")
		)
		(fp_line
			(start -0.32512 0.175006)
			(end -0.32512 -0.175006)
			(stroke
				(width 0.1)
				(type default)
			)
			(layer "F.Fab")
		)
		(fp_line
			(start 0.32512 -0.175006)
			(end 0.32512 0.175006)
			(stroke
				(width 0.1)
				(type default)
			)
			(layer "F.Fab")
		)
		(fp_line
			(start 0.32512 0.175006)
			(end -0.32512 0.175006)
			(stroke
				(width 0.1)
				(type default)
			)
			(layer "F.Fab")
		)
		(pad "1" smd rect
			(at -0.2667 0)
			(size 0.3048 0.381)
			(layers "F.Cu" "F.Mask" "F.Paste")
			(net "JTAG_TRST_RT_CPU1_P0_N")
		)
		(pad "2" smd rect
			(at 0.2667 0 180)
			(size 0.3048 0.381)
			(layers "F.Cu" "F.Mask" "F.Paste")
			(net "GND")
		)
	)
)
